(kicad_pcb
	(version 20260206)
	(generator "pcbnew")
	(generator_version "10.0")
	(general
		(thickness 1.6)
		(legacy_teardrops no)
	)
	(paper "A4")
	(title_block
		(title "04192023_DAF0TMB3IC0_F0TG_MB_C_brd_V02_OCP.brd")
		(comment 1 "Grand Teton / footprints 6909-6916 of 8354")
	)
	(layers
		(0 "F.Cu" signal "TOP")
		(4 "In1.Cu" signal "GND")
		(6 "In2.Cu" signal "IN1")
		(8 "In3.Cu" signal "GND1")
		(10 "In4.Cu" signal "IN2")
		(12 "In5.Cu" signal "GND2")
		(14 "In6.Cu" signal "IN3")
		(16 "In7.Cu" signal "GND3")
		(18 "In8.Cu" signal "VCC")
		(20 "In9.Cu" signal "VCC1")
		(22 "In10.Cu" signal "GND4")
		(24 "In11.Cu" signal "IN4")
		(26 "In12.Cu" signal "GND5")
		(28 "In13.Cu" signal "IN5")
		(30 "In14.Cu" signal "GND6")
		(32 "In15.Cu" signal "IN6")
		(34 "In16.Cu" signal "GND7")
		(2 "B.Cu" signal "BOTTOM")
		(9 "F.Adhes" user "F.Adhesive")
		(11 "B.Adhes" user "B.Adhesive")
		(13 "F.Paste" user "Package Geometry/Pastemask Top")
		(15 "B.Paste" user "Package Geometry/Pastemask Bottom")
		(5 "F.SilkS" user "Ref Des/Silkscreen Top")
		(7 "B.SilkS" user "Ref Des/Silkscreen Bottom")
		(1 "F.Mask" user "Board Geometry/Soldermask Top")
		(3 "B.Mask" user "Board Geometry/Soldermask Bottom")
		(17 "Dwgs.User" user "User.Drawings")
		(19 "Cmts.User" user "User.Comments")
		(21 "Eco1.User" user "User.Eco1")
		(23 "Eco2.User" user "User.Eco2")
		(25 "Edge.Cuts" user "Board Geometry/Outline")
		(27 "Margin" user)
		(31 "F.CrtYd" user "Package Geometry/Place Bound Top")
		(29 "B.CrtYd" user "Package Geometry/Place Bound Bottom")
		(35 "F.Fab" user "Ref Des/Assembly Top")
		(33 "B.Fab" user "Ref Des/Assembly Bottom")
	)
	(footprint ""
		(layer "B.Cu")
		(at 316.034928 -336.054446 -90)
		(property "Reference" "PR88"
			(at 0 0 90)
			(layer "B.SilkS")
			(hide yes)
			(effects
				(font
					(size 1.27 1.27)
				)
				(justify mirror)
			)
		)
		(property "Value" ""
			(at 0 0 90)
			(layer "B.Fab")
			(effects
				(font
					(size 1.27 1.27)
				)
				(justify mirror)
			)
		)
		(duplicate_pad_numbers_are_jumpers no)
		(fp_line
			(start -0.7874 0.4064)
			(end 0.7874 0.4064)
			(stroke
				(width 0.1524)
				(type default)
			)
			(layer "B.SilkS")
		)
		(fp_line
			(start 0.7874 0.4064)
			(end 0.7874 -0.4064)
			(stroke
				(width 0.1524)
				(type default)
			)
			(layer "B.SilkS")
		)
		(fp_line
			(start -0.7874 -0.4064)
			(end -0.7874 0.4064)
			(stroke
				(width 0.1524)
				(type default)
			)
			(layer "B.SilkS")
		)
		(fp_line
			(start 0.7874 -0.4064)
			(end -0.7874 -0.4064)
			(stroke
				(width 0.1524)
				(type default)
			)
			(layer "B.SilkS")
		)
		(fp_line
			(start -0.67945 0.3048)
			(end -0.120396 0.3048)
			(stroke
				(width 0.1)
				(type default)
			)
			(layer "B.Fab")
		)
		(fp_line
			(start -0.120396 0.3048)
			(end -0.120396 0.2794)
			(stroke
				(width 0.1)
				(type default)
			)
			(layer "B.Fab")
		)
		(fp_line
			(start 0.12065 0.3048)
			(end 0.67945 0.3048)
			(stroke
				(width 0.1)
				(type default)
			)
			(layer "B.Fab")
		)
		(fp_line
			(start 0.67945 0.3048)
			(end 0.67945 -0.305054)
			(stroke
				(width 0.1)
				(type default)
			)
			(layer "B.Fab")
		)
		(fp_line
			(start -0.120396 0.2794)
			(end 0.12065 0.2794)
			(stroke
				(width 0.1)
				(type default)
			)
			(layer "B.Fab")
		)
		(fp_line
			(start 0.12065 0.2794)
			(end 0.12065 0.3048)
			(stroke
				(width 0.1)
				(type default)
			)
			(layer "B.Fab")
		)
		(fp_line
			(start -0.12065 -0.2794)
			(end -0.12065 -0.3048)
			(stroke
				(width 0.1)
				(type default)
			)
			(layer "B.Fab")
		)
		(fp_line
			(start 0.12065 -0.2794)
			(end -0.12065 -0.2794)
			(stroke
				(width 0.1)
				(type default)
			)
			(layer "B.Fab")
		)
		(fp_line
			(start -0.67945 -0.3048)
			(end -0.67945 0.3048)
			(stroke
				(width 0.1)
				(type default)
			)
			(layer "B.Fab")
		)
		(fp_line
			(start -0.12065 -0.3048)
			(end -0.67945 -0.3048)
			(stroke
				(width 0.1)
				(type default)
			)
			(layer "B.Fab")
		)
		(fp_line
			(start 0.12065 -0.305054)
			(end 0.12065 -0.2794)
			(stroke
				(width 0.1)
				(type default)
			)
			(layer "B.Fab")
		)
		(fp_line
			(start 0.67945 -0.305054)
			(end 0.12065 -0.305054)
			(stroke
				(width 0.1)
				(type default)
			)
			(layer "B.Fab")
		)
		(pad "1" smd circle
			(at 0.40005 0 90)
			(size 0 0)
			(layers "B.Cu" "B.Mask" "B.Paste")
			(net "PVDDCR_CPU1_P0_PVCC")
		)
		(pad "2" smd circle
			(at -0.40005 0 90)
			(size 0 0)
			(layers "B.Cu" "B.Mask" "B.Paste")
			(net "PVDDCR_CPU1_P0_VCC3")
		)
	)
	(footprint ""
		(layer "B.Cu")
		(at 301.082202 -427.668436 90)
		(property "Reference" "R1411"
			(at 0 0 90)
			(layer "B.SilkS")
			(hide yes)
			(effects
				(font
					(size 1.27 1.27)
				)
				(justify mirror)
			)
		)
		(property "Value" ""
			(at 0 0 90)
			(layer "B.Fab")
			(effects
				(font
					(size 1.27 1.27)
				)
				(justify mirror)
			)
		)
		(duplicate_pad_numbers_are_jumpers no)
		(fp_line
			(start 0.32512 -0.175006)
			(end -0.32512 -0.175006)
			(stroke
				(width 0.1)
				(type default)
			)
			(layer "B.Fab")
		)
		(fp_line
			(start -0.32512 -0.175006)
			(end -0.32512 0.175006)
			(stroke
				(width 0.1)
				(type default)
			)
			(layer "B.Fab")
		)
		(fp_line
			(start 0.32512 0.175006)
			(end 0.32512 -0.175006)
			(stroke
				(width 0.1)
				(type default)
			)
			(layer "B.Fab")
		)
		(fp_line
			(start -0.32512 0.175006)
			(end 0.32512 0.175006)
			(stroke
				(width 0.1)
				(type default)
			)
			(layer "B.Fab")
		)
		(pad "1" smd rect
			(at 0.2667 0 270)
			(size 0.3048 0.381)
			(layers "B.Cu" "B.Mask" "B.Paste")
			(net "P1V8_CPU0_RT_1D")
		)
		(pad "2" smd rect
			(at -0.2667 0 90)
			(size 0.3048 0.381)
			(layers "B.Cu" "B.Mask" "B.Paste")
			(net "SMB_RT_CPU0_P0_ROM_MUX_1D_SCL")
		)
	)
	(footprint ""
		(layer "B.Cu")
		(at 201.041 -137.922 90)
		(property "Reference" "C8013"
			(at 0 0 90)
			(layer "B.SilkS")
			(hide yes)
			(effects
				(font
					(size 1.27 1.27)
				)
				(justify mirror)
			)
		)
		(property "Value" ""
			(at 0 0 90)
			(layer "B.Fab")
			(effects
				(font
					(size 1.27 1.27)
				)
				(justify mirror)
			)
		)
		(duplicate_pad_numbers_are_jumpers no)
		(fp_line
			(start 0.7874 -0.4064)
			(end -0.7874 -0.4064)
			(stroke
				(width 0.1524)
				(type default)
			)
			(layer "B.SilkS")
		)
		(fp_line
			(start -0.7874 -0.4064)
			(end -0.7874 0.4064)
			(stroke
				(width 0.1524)
				(type default)
			)
			(layer "B.SilkS")
		)
		(fp_line
			(start 0.7874 0.4064)
			(end 0.7874 -0.4064)
			(stroke
				(width 0.1524)
				(type default)
			)
			(layer "B.SilkS")
		)
		(fp_line
			(start -0.7874 0.4064)
			(end 0.7874 0.4064)
			(stroke
				(width 0.1524)
				(type default)
			)
			(layer "B.SilkS")
		)
		(fp_line
			(start 0.67945 -0.305054)
			(end 0.12065 -0.305054)
			(stroke
				(width 0.1)
				(type default)
			)
			(layer "B.Fab")
		)
		(fp_line
			(start 0.12065 -0.305054)
			(end 0.12065 -0.2794)
			(stroke
				(width 0.1)
				(type default)
			)
			(layer "B.Fab")
		)
		(fp_line
			(start -0.12065 -0.3048)
			(end -0.67945 -0.3048)
			(stroke
				(width 0.1)
				(type default)
			)
			(layer "B.Fab")
		)
		(fp_line
			(start -0.67945 -0.3048)
			(end -0.67945 0.3048)
			(stroke
				(width 0.1)
				(type default)
			)
			(layer "B.Fab")
		)
		(fp_line
			(start 0.12065 -0.2794)
			(end -0.12065 -0.2794)
			(stroke
				(width 0.1)
				(type default)
			)
			(layer "B.Fab")
		)
		(fp_line
			(start -0.12065 -0.2794)
			(end -0.12065 -0.3048)
			(stroke
				(width 0.1)
				(type default)
			)
			(layer "B.Fab")
		)
		(fp_line
			(start 0.12065 0.2794)
			(end 0.12065 0.3048)
			(stroke
				(width 0.1)
				(type default)
			)
			(layer "B.Fab")
		)
		(fp_line
			(start -0.120396 0.2794)
			(end 0.12065 0.2794)
			(stroke
				(width 0.1)
				(type default)
			)
			(layer "B.Fab")
		)
		(fp_line
			(start 0.67945 0.3048)
			(end 0.67945 -0.305054)
			(stroke
				(width 0.1)
				(type default)
			)
			(layer "B.Fab")
		)
		(fp_line
			(start 0.12065 0.3048)
			(end 0.67945 0.3048)
			(stroke
				(width 0.1)
				(type default)
			)
			(layer "B.Fab")
		)
		(fp_line
			(start -0.120396 0.3048)
			(end -0.120396 0.2794)
			(stroke
				(width 0.1)
				(type default)
			)
			(layer "B.Fab")
		)
		(fp_line
			(start -0.67945 0.3048)
			(end -0.120396 0.3048)
			(stroke
				(width 0.1)
				(type default)
			)
			(layer "B.Fab")
		)
		(pad "1" smd circle
			(at 0.40005 0 270)
			(size 0 0)
			(layers "B.Cu" "B.Mask" "B.Paste")
			(net "P3V3_AUX")
		)
		(pad "2" smd circle
			(at -0.40005 0 270)
			(size 0 0)
			(layers "B.Cu" "B.Mask" "B.Paste")
			(net "GND")
		)
	)
	(footprint ""
		(layer "B.Cu")
		(at 37.792914 -244.085364 180)
		(property "Reference" "R503"
			(at 0 0 0)
			(layer "B.SilkS")
			(hide yes)
			(effects
				(font
					(size 1.27 1.27)
				)
				(justify mirror)
			)
		)
		(property "Value" ""
			(at 0 0 0)
			(layer "B.Fab")
			(effects
				(font
					(size 1.27 1.27)
				)
				(justify mirror)
			)
		)
		(duplicate_pad_numbers_are_jumpers no)
		(fp_line
			(start 0.7874 0.4064)
			(end 0.7874 -0.4064)
			(stroke
				(width 0.1524)
				(type default)
			)
			(layer "B.SilkS")
		)
		(fp_line
			(start 0.7874 -0.4064)
			(end -0.7874 -0.4064)
			(stroke
				(width 0.1524)
				(type default)
			)
			(layer "B.SilkS")
		)
		(fp_line
			(start -0.7874 0.4064)
			(end 0.7874 0.4064)
			(stroke
				(width 0.1524)
				(type default)
			)
			(layer "B.SilkS")
		)
		(fp_line
			(start -0.7874 -0.4064)
			(end -0.7874 0.4064)
			(stroke
				(width 0.1524)
				(type default)
			)
			(layer "B.SilkS")
		)
		(fp_line
			(start 0.67945 0.3048)
			(end 0.67945 -0.305054)
			(stroke
				(width 0.1)
				(type default)
			)
			(layer "B.Fab")
		)
		(fp_line
			(start 0.67945 -0.305054)
			(end 0.12065 -0.305054)
			(stroke
				(width 0.1)
				(type default)
			)
			(layer "B.Fab")
		)
		(fp_line
			(start 0.12065 0.3048)
			(end 0.67945 0.3048)
			(stroke
				(width 0.1)
				(type default)
			)
			(layer "B.Fab")
		)
		(fp_line
			(start 0.12065 0.2794)
			(end 0.12065 0.3048)
			(stroke
				(width 0.1)
				(type default)
			)
			(layer "B.Fab")
		)
		(fp_line
			(start 0.12065 -0.2794)
			(end -0.12065 -0.2794)
			(stroke
				(width 0.1)
				(type default)
			)
			(layer "B.Fab")
		)
		(fp_line
			(start 0.12065 -0.305054)
			(end 0.12065 -0.2794)
			(stroke
				(width 0.1)
				(type default)
			)
			(layer "B.Fab")
		)
		(fp_line
			(start -0.120396 0.3048)
			(end -0.120396 0.2794)
			(stroke
				(width 0.1)
				(type default)
			)
			(layer "B.Fab")
		)
		(fp_line
			(start -0.120396 0.2794)
			(end 0.12065 0.2794)
			(stroke
				(width 0.1)
				(type default)
			)
			(layer "B.Fab")
		)
		(fp_line
			(start -0.12065 -0.2794)
			(end -0.12065 -0.3048)
			(stroke
				(width 0.1)
				(type default)
			)
			(layer "B.Fab")
		)
		(fp_line
			(start -0.12065 -0.3048)
			(end -0.67945 -0.3048)
			(stroke
				(width 0.1)
				(type default)
			)
			(layer "B.Fab")
		)
		(fp_line
			(start -0.67945 0.3048)
			(end -0.120396 0.3048)
			(stroke
				(width 0.1)
				(type default)
			)
			(layer "B.Fab")
		)
		(fp_line
			(start -0.67945 -0.3048)
			(end -0.67945 0.3048)
			(stroke
				(width 0.1)
				(type default)
			)
			(layer "B.Fab")
		)
		(pad "1" smd circle
			(at 0.40005 0)
			(size 0 0)
			(layers "B.Cu" "B.Mask" "B.Paste")
			(net "M_D_CPU1_ALERT_N")
		)
		(pad "2" smd circle
			(at -0.40005 0)
			(size 0 0)
			(layers "B.Cu" "B.Mask" "B.Paste")
			(net "M_D_CPU1_ALERT_R_N")
		)
	)
	(footprint ""
		(layer "B.Cu")
		(at 93.10624 -386.766562 90)
		(property "Reference" "C315"
			(at 0 0 90)
			(layer "B.SilkS")
			(hide yes)
			(effects
				(font
					(size 1.27 1.27)
				)
				(justify mirror)
			)
		)
		(property "Value" ""
			(at 0 0 90)
			(layer "B.Fab")
			(effects
				(font
					(size 1.27 1.27)
				)
				(justify mirror)
			)
		)
		(duplicate_pad_numbers_are_jumpers no)
		(fp_line
			(start 0.299974 -0.150114)
			(end -0.299974 -0.150114)
			(stroke
				(width 0.1)
				(type default)
			)
			(layer "B.Fab")
		)
		(fp_line
			(start -0.299974 -0.150114)
			(end -0.299974 0.150114)
			(stroke
				(width 0.1)
				(type default)
			)
			(layer "B.Fab")
		)
		(fp_line
			(start 0.299974 0.150114)
			(end 0.299974 -0.150114)
			(stroke
				(width 0.1)
				(type default)
			)
			(layer "B.Fab")
		)
		(fp_line
			(start -0.299974 0.150114)
			(end 0.299974 0.150114)
			(stroke
				(width 0.1)
				(type default)
			)
			(layer "B.Fab")
		)
		(pad "1" smd rect
			(at 0.2667 0 270)
			(size 0.3048 0.381)
			(layers "B.Cu" "B.Mask" "B.Paste")
			(net "P0V9_CPU1_RT1_2A_2D")
		)
		(pad "2" smd rect
			(at -0.2667 0 270)
			(size 0.3048 0.381)
			(layers "B.Cu" "B.Mask" "B.Paste")
			(net "GND")
		)
	)
	(footprint ""
		(layer "B.Cu")
		(at 112.054386 -267.529564 -90)
		(property "Reference" "C2377"
			(at 0 0 90)
			(layer "B.SilkS")
			(hide yes)
			(effects
				(font
					(size 1.27 1.27)
				)
				(justify mirror)
			)
		)
		(property "Value" ""
			(at 0 0 90)
			(layer "B.Fab")
			(effects
				(font
					(size 1.27 1.27)
				)
				(justify mirror)
			)
		)
		(duplicate_pad_numbers_are_jumpers no)
		(fp_line
			(start -0.7874 0.4064)
			(end 0.7874 0.4064)
			(stroke
				(width 0.1524)
				(type default)
			)
			(layer "B.SilkS")
		)
		(fp_line
			(start 0.7874 0.4064)
			(end 0.7874 -0.4064)
			(stroke
				(width 0.1524)
				(type default)
			)
			(layer "B.SilkS")
		)
		(fp_line
			(start -0.7874 -0.4064)
			(end -0.7874 0.4064)
			(stroke
				(width 0.1524)
				(type default)
			)
			(layer "B.SilkS")
		)
		(fp_line
			(start 0.7874 -0.4064)
			(end -0.7874 -0.4064)
			(stroke
				(width 0.1524)
				(type default)
			)
			(layer "B.SilkS")
		)
		(fp_line
			(start -0.67945 0.3048)
			(end -0.120396 0.3048)
			(stroke
				(width 0.1)
				(type default)
			)
			(layer "B.Fab")
		)
		(fp_line
			(start -0.120396 0.3048)
			(end -0.120396 0.2794)
			(stroke
				(width 0.1)
				(type default)
			)
			(layer "B.Fab")
		)
		(fp_line
			(start 0.12065 0.3048)
			(end 0.67945 0.3048)
			(stroke
				(width 0.1)
				(type default)
			)
			(layer "B.Fab")
		)
		(fp_line
			(start 0.67945 0.3048)
			(end 0.67945 -0.305054)
			(stroke
				(width 0.1)
				(type default)
			)
			(layer "B.Fab")
		)
		(fp_line
			(start -0.120396 0.2794)
			(end 0.12065 0.2794)
			(stroke
				(width 0.1)
				(type default)
			)
			(layer "B.Fab")
		)
		(fp_line
			(start 0.12065 0.2794)
			(end 0.12065 0.3048)
			(stroke
				(width 0.1)
				(type default)
			)
			(layer "B.Fab")
		)
		(fp_line
			(start -0.12065 -0.2794)
			(end -0.12065 -0.3048)
			(stroke
				(width 0.1)
				(type default)
			)
			(layer "B.Fab")
		)
		(fp_line
			(start 0.12065 -0.2794)
			(end -0.12065 -0.2794)
			(stroke
				(width 0.1)
				(type default)
			)
			(layer "B.Fab")
		)
		(fp_line
			(start -0.67945 -0.3048)
			(end -0.67945 0.3048)
			(stroke
				(width 0.1)
				(type default)
			)
			(layer "B.Fab")
		)
		(fp_line
			(start -0.12065 -0.3048)
			(end -0.67945 -0.3048)
			(stroke
				(width 0.1)
				(type default)
			)
			(layer "B.Fab")
		)
		(fp_line
			(start 0.12065 -0.305054)
			(end 0.12065 -0.2794)
			(stroke
				(width 0.1)
				(type default)
			)
			(layer "B.Fab")
		)
		(fp_line
			(start 0.67945 -0.305054)
			(end 0.12065 -0.305054)
			(stroke
				(width 0.1)
				(type default)
			)
			(layer "B.Fab")
		)
		(pad "1" smd circle
			(at 0.40005 0 90)
			(size 0 0)
			(layers "B.Cu" "B.Mask" "B.Paste")
			(net "PVDDCR_CPU1_P1")
		)
		(pad "2" smd circle
			(at -0.40005 0 90)
			(size 0 0)
			(layers "B.Cu" "B.Mask" "B.Paste")
			(net "GND")
		)
	)
	(footprint ""
		(layer "B.Cu")
		(at 150.095966 -408.517344 90)
		(property "Reference" "C6748"
			(at 0 0 90)
			(layer "B.SilkS")
			(hide yes)
			(effects
				(font
					(size 1.27 1.27)
				)
				(justify mirror)
			)
		)
		(property "Value" ""
			(at 0 0 90)
			(layer "B.Fab")
			(effects
				(font
					(size 1.27 1.27)
				)
				(justify mirror)
			)
		)
		(duplicate_pad_numbers_are_jumpers no)
		(fp_line
			(start 0.299974 -0.150114)
			(end -0.299974 -0.150114)
			(stroke
				(width 0.1)
				(type default)
			)
			(layer "B.Fab")
		)
		(fp_line
			(start -0.299974 -0.150114)
			(end -0.299974 0.150114)
			(stroke
				(width 0.1)
				(type default)
			)
			(layer "B.Fab")
		)
		(fp_line
			(start 0.299974 0.150114)
			(end 0.299974 -0.150114)
			(stroke
				(width 0.1)
				(type default)
			)
			(layer "B.Fab")
		)
		(fp_line
			(start -0.299974 0.150114)
			(end 0.299974 0.150114)
			(stroke
				(width 0.1)
				(type default)
			)
			(layer "B.Fab")
		)
		(pad "1" smd rect
			(at 0.2667 0 270)
			(size 0.3048 0.381)
			(layers "B.Cu" "B.Mask" "B.Paste")
			(net "P5E_CPU1_P3_TX_BUF_C_DN<11>")
		)
		(pad "2" smd rect
			(at -0.2667 0 270)
			(size 0.3048 0.381)
			(layers "B.Cu" "B.Mask" "B.Paste")
			(net "P5E_CPU1_P3_TX_BUF_DN<11>")
		)
	)
	(footprint ""
		(layer "B.Cu")
		(at 42.875962 -347.780356 -90)
		(property "Reference" "PR276"
			(at 0 0 90)
			(layer "B.SilkS")
			(hide yes)
			(effects
				(font
					(size 1.27 1.27)
				)
				(justify mirror)
			)
		)
		(property "Value" ""
			(at 0 0 90)
			(layer "B.Fab")
			(effects
				(font
					(size 1.27 1.27)
				)
				(justify mirror)
			)
		)
		(duplicate_pad_numbers_are_jumpers no)
		(fp_line
			(start -0.7874 0.4064)
			(end 0.7874 0.4064)
			(stroke
				(width 0.1524)
				(type default)
			)
			(layer "B.SilkS")
		)
		(fp_line
			(start 0.7874 0.4064)
			(end 0.7874 -0.4064)
			(stroke
				(width 0.1524)
				(type default)
			)
			(layer "B.SilkS")
		)
		(fp_line
			(start -0.7874 -0.4064)
			(end -0.7874 0.4064)
			(stroke
				(width 0.1524)
				(type default)
			)
			(layer "B.SilkS")
		)
		(fp_line
			(start 0.7874 -0.4064)
			(end -0.7874 -0.4064)
			(stroke
				(width 0.1524)
				(type default)
			)
			(layer "B.SilkS")
		)
		(fp_line
			(start -0.67945 0.3048)
			(end -0.120396 0.3048)
			(stroke
				(width 0.1)
				(type default)
			)
			(layer "B.Fab")
		)
		(fp_line
			(start -0.120396 0.3048)
			(end -0.120396 0.2794)
			(stroke
				(width 0.1)
				(type default)
			)
			(layer "B.Fab")
		)
		(fp_line
			(start 0.12065 0.3048)
			(end 0.67945 0.3048)
			(stroke
				(width 0.1)
				(type default)
			)
			(layer "B.Fab")
		)
		(fp_line
			(start 0.67945 0.3048)
			(end 0.67945 -0.305054)
			(stroke
				(width 0.1)
				(type default)
			)
			(layer "B.Fab")
		)
		(fp_line
			(start -0.120396 0.2794)
			(end 0.12065 0.2794)
			(stroke
				(width 0.1)
				(type default)
			)
			(layer "B.Fab")
		)
		(fp_line
			(start 0.12065 0.2794)
			(end 0.12065 0.3048)
			(stroke
				(width 0.1)
				(type default)
			)
			(layer "B.Fab")
		)
		(fp_line
			(start -0.12065 -0.2794)
			(end -0.12065 -0.3048)
			(stroke
				(width 0.1)
				(type default)
			)
			(layer "B.Fab")
		)
		(fp_line
			(start 0.12065 -0.2794)
			(end -0.12065 -0.2794)
			(stroke
				(width 0.1)
				(type default)
			)
			(layer "B.Fab")
		)
		(fp_line
			(start -0.67945 -0.3048)
			(end -0.67945 0.3048)
			(stroke
				(width 0.1)
				(type default)
			)
			(layer "B.Fab")
		)
		(fp_line
			(start -0.12065 -0.3048)
			(end -0.67945 -0.3048)
			(stroke
				(width 0.1)
				(type default)
			)
			(layer "B.Fab")
		)
		(fp_line
			(start 0.12065 -0.305054)
			(end 0.12065 -0.2794)
			(stroke
				(width 0.1)
				(type default)
			)
			(layer "B.Fab")
		)
		(fp_line
			(start 0.67945 -0.305054)
			(end 0.12065 -0.305054)
			(stroke
				(width 0.1)
				(type default)
			)
			(layer "B.Fab")
		)
		(pad "1" smd circle
			(at 0.40005 0 90)
			(size 0 0)
			(layers "B.Cu" "B.Mask" "B.Paste")
			(net "PVDDCR_CPU1_P1_PVCC")
		)
		(pad "2" smd circle
			(at -0.40005 0 90)
			(size 0 0)
			(layers "B.Cu" "B.Mask" "B.Paste")
			(net "PVDDIO_P1_VCC2")
		)
	)
)
